# S9S_MB_2U (Grand Teton) — schematic netlist excerpt (pin names and nets, part order shuffled) for the footprints in the layout excerpt that follows; sources: Cadence DE-HDL packaged netlist, KiCad conversion of 03242023_DA0F0TMBIJ0_F0T_Motherboard_J_brd_V01_OCP.brd

C752  Q_CAP_DIFFBUS  DIFF BUS_0.22UF 6.3V 20% X6S  pkg C0201  page 176 : \1\ = P5E_CPU1_PE2_TX_C_DN<10> ; \2\ = P5E_CPU1_PE2_TX_DN<10>
R1811  Q_RES  33.2 1% CHIP  pkg 0402LF  page 222 : A = RST_SGPIO_RESET_N ; B = RST_SGPIO_RESET_N_R
R4091  Q_RES  4.7K 1% CHIP  pkg 0402LF  page 172 : A = P3V3_AUX ; B = P12V_SCM_ADC_ALERT_R

(kicad_pcb
	(version 20260206)
	(generator "pcbnew")
	(generator_version "10.0")
	(general
		(thickness 1.6)
		(legacy_teardrops no)
	)
	(paper "A4")
	(title_block
		(title "03242023_DA0F0TMBIJ0_F0T_Motherboard_J_brd_V01_OCP.brd")
		(comment 1 "Grand Teton / footprints 2976-2978 of 6105")
	)
	(layers
		(0 "F.Cu" signal "TOP")
		(4 "In1.Cu" signal "GND")
		(6 "In2.Cu" signal "IN1")
		(8 "In3.Cu" signal "GND1")
		(10 "In4.Cu" signal "IN2")
		(12 "In5.Cu" signal "GND2")
		(14 "In6.Cu" signal "IN3")
		(16 "In7.Cu" signal "GND3")
		(18 "In8.Cu" signal "VCC")
		(20 "In9.Cu" signal "VCC1")
		(22 "In10.Cu" signal "GND4")
		(24 "In11.Cu" signal "IN4")
		(26 "In12.Cu" signal "GND5")
		(28 "In13.Cu" signal "IN5")
		(30 "In14.Cu" signal "GND6")
		(32 "In15.Cu" signal "IN6")
		(34 "In16.Cu" signal "GND7")
		(2 "B.Cu" signal "BOTTOM")
		(9 "F.Adhes" user "F.Adhesive")
		(11 "B.Adhes" user "B.Adhesive")
		(13 "F.Paste" user "Package Geometry/Pastemask Top")
		(15 "B.Paste" user "Package Geometry/Pastemask Bottom")
		(5 "F.SilkS" user "Ref Des/Silkscreen Top")
		(7 "B.SilkS" user "Ref Des/Silkscreen Bottom")
		(1 "F.Mask" user "Board Geometry/Soldermask Top")
		(3 "B.Mask" user "Board Geometry/Soldermask Bottom")
		(17 "Dwgs.User" user "User.Drawings")
		(19 "Cmts.User" user "User.Comments")
		(21 "Eco1.User" user "User.Eco1")
		(23 "Eco2.User" user "User.Eco2")
		(25 "Edge.Cuts" user "Board Geometry/Outline")
		(27 "Margin" user)
		(31 "F.CrtYd" user "Package Geometry/Place Bound Top")
		(29 "B.CrtYd" user "Package Geometry/Place Bound Bottom")
		(35 "F.Fab" user "Ref Des/Assembly Top")
		(33 "B.Fab" user "Ref Des/Assembly Bottom")
	)
	(footprint ""
		(layer "F.Cu")
		(at 197.19036 -116.804948 180)
		(property "Reference" "R1811"
			(at 0 0 180)
			(layer "F.SilkS")
			(hide yes)
			(effects
				(font
					(size 1.27 1.27)
				)
			)
		)
		(property "Value" ""
			(at 0 0 180)
			(layer "F.Fab")
			(effects
				(font
					(size 1.27 1.27)
				)
			)
		)
		(duplicate_pad_numbers_are_jumpers no)
		(fp_line
			(start 0.7874 0.4064)
			(end -0.7874 0.4064)
			(stroke
				(width 0.1524)
				(type default)
			)
			(layer "F.SilkS")
		)
		(fp_line
			(start 0.7874 -0.4064)
			(end 0.7874 0.4064)
			(stroke
				(width 0.1524)
				(type default)
			)
			(layer "F.SilkS")
		)
		(fp_line
			(start -0.7874 0.4064)
			(end -0.7874 -0.4064)
			(stroke
				(width 0.1524)
				(type default)
			)
			(layer "F.SilkS")
		)
		(fp_line
			(start -0.7874 -0.4064)
			(end 0.7874 -0.4064)
			(stroke
				(width 0.1524)
				(type default)
			)
			(layer "F.SilkS")
		)
		(fp_line
			(start 0.67945 0.3048)
			(end 0.120396 0.3048)
			(stroke
				(width 0.1)
				(type default)
			)
			(layer "F.Fab")
		)
		(fp_line
			(start 0.67945 -0.3048)
			(end 0.67945 0.3048)
			(stroke
				(width 0.1)
				(type default)
			)
			(layer "F.Fab")
		)
		(fp_line
			(start 0.12065 -0.2794)
			(end 0.12065 -0.3048)
			(stroke
				(width 0.1)
				(type default)
			)
			(layer "F.Fab")
		)
		(fp_line
			(start 0.12065 -0.3048)
			(end 0.67945 -0.3048)
			(stroke
				(width 0.1)
				(type default)
			)
			(layer "F.Fab")
		)
		(fp_line
			(start 0.120396 0.3048)
			(end 0.120396 0.2794)
			(stroke
				(width 0.1)
				(type default)
			)
			(layer "F.Fab")
		)
		(fp_line
			(start 0.120396 0.2794)
			(end -0.12065 0.2794)
			(stroke
				(width 0.1)
				(type default)
			)
			(layer "F.Fab")
		)
		(fp_line
			(start -0.12065 0.3048)
			(end -0.67945 0.3048)
			(stroke
				(width 0.1)
				(type default)
			)
			(layer "F.Fab")
		)
		(fp_line
			(start -0.12065 0.2794)
			(end -0.12065 0.3048)
			(stroke
				(width 0.1)
				(type default)
			)
			(layer "F.Fab")
		)
		(fp_line
			(start -0.12065 -0.2794)
			(end 0.12065 -0.2794)
			(stroke
				(width 0.1)
				(type default)
			)
			(layer "F.Fab")
		)
		(fp_line
			(start -0.12065 -0.305054)
			(end -0.12065 -0.2794)
			(stroke
				(width 0.1)
				(type default)
			)
			(layer "F.Fab")
		)
		(fp_line
			(start -0.67945 0.3048)
			(end -0.67945 -0.305054)
			(stroke
				(width 0.1)
				(type default)
			)
			(layer "F.Fab")
		)
		(fp_line
			(start -0.67945 -0.305054)
			(end -0.12065 -0.305054)
			(stroke
				(width 0.1)
				(type default)
			)
			(layer "F.Fab")
		)
		(pad "1" smd circle
			(at -0.40005 0 180)
			(size 0 0)
			(layers "F.Cu" "F.Mask" "F.Paste")
			(net "RST_SGPIO_RESET_N")
		)
		(pad "2" smd circle
			(at 0.40005 0 180)
			(size 0 0)
			(layers "F.Cu" "F.Mask" "F.Paste")
			(net "RST_SGPIO_RESET_N_R")
		)
	)
	(footprint ""
		(layer "F.Cu")
		(at 136.360154 -402.371052 -90)
		(property "Reference" "C752"
			(at 0 0 270)
			(layer "F.SilkS")
			(hide yes)
			(effects
				(font
					(size 1.27 1.27)
				)
			)
		)
		(property "Value" ""
			(at 0 0 270)
			(layer "F.Fab")
			(effects
				(font
					(size 1.27 1.27)
				)
			)
		)
		(duplicate_pad_numbers_are_jumpers no)
		(fp_line
			(start -0.299974 0.150114)
			(end -0.299974 -0.150114)
			(stroke
				(width 0.1)
				(type default)
			)
			(layer "F.Fab")
		)
		(fp_line
			(start 0.299974 0.150114)
			(end -0.299974 0.150114)
			(stroke
				(width 0.1)
				(type default)
			)
			(layer "F.Fab")
		)
		(fp_line
			(start -0.299974 -0.150114)
			(end 0.299974 -0.150114)
			(stroke
				(width 0.1)
				(type default)
			)
			(layer "F.Fab")
		)
		(fp_line
			(start 0.299974 -0.150114)
			(end 0.299974 0.150114)
			(stroke
				(width 0.1)
				(type default)
			)
			(layer "F.Fab")
		)
		(pad "1" smd rect
			(at -0.2667 0 270)
			(size 0.3048 0.381)
			(layers "F.Cu" "F.Mask" "F.Paste")
			(net "P5E_CPU1_PE2_TX_C_DN<10>")
		)
		(pad "2" smd rect
			(at 0.2667 0 270)
			(size 0.3048 0.381)
			(layers "F.Cu" "F.Mask" "F.Paste")
			(net "P5E_CPU1_PE2_TX_DN<10>")
		)
	)
	(footprint ""
		(layer "F.Cu")
		(at 213.19744 -30.246828 90)
		(property "Reference" "R4091"
			(at 0 0 90)
			(layer "F.SilkS")
			(hide yes)
			(effects
				(font
					(size 1.27 1.27)
				)
			)
		)
		(property "Value" ""
			(at 0 0 90)
			(layer "F.Fab")
			(effects
				(font
					(size 1.27 1.27)
				)
			)
		)
		(duplicate_pad_numbers_are_jumpers no)
		(fp_line
			(start 0.7874 -0.4064)
			(end 0.7874 0.4064)
			(stroke
				(width 0.1524)
				(type default)
			)
			(layer "F.SilkS")
		)
		(fp_line
			(start -0.7874 -0.4064)
			(end 0.7874 -0.4064)
			(stroke
				(width 0.1524)
				(type default)
			)
			(layer "F.SilkS")
		)
		(fp_line
			(start 0.7874 0.4064)
			(end -0.7874 0.4064)
			(stroke
				(width 0.1524)
				(type default)
			)
			(layer "F.SilkS")
		)
		(fp_line
			(start -0.7874 0.4064)
			(end -0.7874 -0.4064)
			(stroke
				(width 0.1524)
				(type default)
			)
			(layer "F.SilkS")
		)
		(fp_line
			(start -0.12065 -0.305054)
			(end -0.12065 -0.2794)
			(stroke
				(width 0.1)
				(type default)
			)
			(layer "F.Fab")
		)
		(fp_line
			(start -0.67945 -0.305054)
			(end -0.12065 -0.305054)
			(stroke
				(width 0.1)
				(type default)
			)
			(layer "F.Fab")
		)
		(fp_line
			(start 0.67945 -0.3048)
			(end 0.67945 0.3048)
			(stroke
				(width 0.1)
				(type default)
			)
			(layer "F.Fab")
		)
		(fp_line
			(start 0.12065 -0.3048)
			(end 0.67945 -0.3048)
			(stroke
				(width 0.1)
				(type default)
			)
			(layer "F.Fab")
		)
		(fp_line
			(start 0.12065 -0.2794)
			(end 0.12065 -0.3048)
			(stroke
				(width 0.1)
				(type default)
			)
			(layer "F.Fab")
		)
		(fp_line
			(start -0.12065 -0.2794)
			(end 0.12065 -0.2794)
			(stroke
				(width 0.1)
				(type default)
			)
			(layer "F.Fab")
		)
		(fp_line
			(start 0.120396 0.2794)
			(end -0.12065 0.2794)
			(stroke
				(width 0.1)
				(type default)
			)
			(layer "F.Fab")
		)
		(fp_line
			(start -0.12065 0.2794)
			(end -0.12065 0.3048)
			(stroke
				(width 0.1)
				(type default)
			)
			(layer "F.Fab")
		)
		(fp_line
			(start 0.67945 0.3048)
			(end 0.120396 0.3048)
			(stroke
				(width 0.1)
				(type default)
			)
			(layer "F.Fab")
		)
		(fp_line
			(start 0.120396 0.3048)
			(end 0.120396 0.2794)
			(stroke
				(width 0.1)
				(type default)
			)
			(layer "F.Fab")
		)
		(fp_line
			(start -0.12065 0.3048)
			(end -0.67945 0.3048)
			(stroke
				(width 0.1)
				(type default)
			)
			(layer "F.Fab")
		)
		(fp_line
			(start -0.67945 0.3048)
			(end -0.67945 -0.305054)
			(stroke
				(width 0.1)
				(type default)
			)
			(layer "F.Fab")
		)
		(pad "1" smd circle
			(at -0.40005 0 90)
			(size 0 0)
			(layers "F.Cu" "F.Mask" "F.Paste")
			(net "P3V3_AUX")
		)
		(pad "2" smd circle
			(at 0.40005 0 90)
			(size 0 0)
			(layers "F.Cu" "F.Mask" "F.Paste")
			(net "P12V_SCM_ADC_ALERT_R")
		)
	)
)
